FILE_TYPE = CONNECTIVITY;
{Allegro Design Entry HDL 16.6-p007 (v16-6-112F) 10/10/2012}
"PAGE_NUMBER" = 268;
0"NC";
1"GND\g";
2"P3V3_STBY\g";
3"GND\g";
4"GND\g";
5"GND\g";
6"GND\g";
7"P3V3_STBY\g";
8"GND\g";
9"P3V3_STBY\g";
10"P1V05_PCH_STBY\g";
11"GND\g";
12"P3V3_STBY\g";
13"P3V3_STBY\g";
14"GND\g";
15"GND\g";
16"GND\g";
17"P3V3_STBY\g";
18"P3V3_STBY\g";
19"GND\g";
20"P3V3_STBY\g";
21"GND\g";
22"GND\g";
23"P3V3_STBY\g";
24"XDP_PRESENT_N";
25"P0V7_GTL2014_VREF_6"VOLTAGE"+0.7 V";
26"PD_GTL2014_6_B2";
27"BMC_PRDY_N";
28"TP_GTL2014_6_A2";
29"BMC_JTAG_SEL_N";
30"PD_GTL2014_DIR_6";
31"JTAG_BMC_BUF_TDO";
32"JTAG_BMC_BUF_TDO_R";
33"TP_GTL2014_6_A0";
34"CPU_XDP_PRESENT_N";
35"BMC_JTAG_SEL";
36"JTAG_BMC_TMS";
37"JTAG_BMC_TDI";
38"BMC_JTAG_SEL_BUF";
39"BMC_DEBUG_EN_N";
40"XDP_PRDY_N";
41"XDP_TDO";
42"PD_GTL2014_6_B0";
43"XDP_PRESENT_N";
44"JTAG_BMC_BUF_TMS";
45"JTAG_BMC_BUF_TDO";
46"BMC_PWR_DEBUG_BUF_N";
47"BMC_PWR_DEBUG_N";
48"JTAG_BMC_TDO";
49"JTAG_BMC_BUF_TDI";
%"GND"
"1","(-6700,3975)","0","mstr_symbols","I10";
;
SIZE"1B"
CDS_LIB"mstr_symbols"
VOLTAGE"0.0V"
BODY_TYPE"PLUMBING"
HDL_POWER"GND";
"A\NAC"1;
%"P3V3_STBY"
"1","(-6700,4350)","0","mstr_symbols","I11";
;
VOLTAGE"3.3V"
SIZE"1B"
CDS_LIB"mstr_symbols"
BODY_TYPE"PLUMBING"
HDL_POWER"P3V3_STBY";
"G\NAC"2;
%"TTL1G07_A"
"1","(-6300,3100)","0","mstr_ttl","I12";
;
LOCATION"U25W15"
PART_NUMBER"C88419-001"
VALUE"74LVC1G07"
POWER_GROUP"VCC=P3V3_STBY;GND=GND"
MATERIAL"IC"
CDS_LOCATION"U25W15"
PACK_TYPE"SOP"
BOM_COST"SM_THERM"
SEC_TYPE"SOP"
SEC"1"
ROOM"CPU_FANS"
CDS_LIB"mstr_ttl"
CDS_SEC"1";
"Y"
$PN"4"34;
"A"
$PN"2"39;
%"TTL1G07_A"
"1","(-6300,3900)","0","mstr_ttl","I13";
;
POWER_GROUP"VCC=P3V3_STBY;GND=GND"
PART_NUMBER"C88419-001"
MATERIAL"IC"
VALUE"74LVC1G07"
LOCATION"U25W14"
CDS_LOCATION"U25W14"
PACK_TYPE"SOP"
BOM_COST"SM_THERM"
SEC_TYPE"SOP"
SEC"1"
ROOM"CPU_FANS"
CDS_LIB"mstr_ttl"
CDS_SEC"1";
"Y"
$PN"4"34;
"A"
$PN"2"43;
%"RES"
"2","(-8450,4950)","0","mstr_discrete","I14";
;
TOLERANCE"1%"
PACK_TYPE"0402"
PART_NUMBER"G21796-026"
MATERIAL"CHIP"
WATTAGE"1/16W"
VALUE"1.00K"
LOCATION"R25W176"
CDS_LOCATION"R25W176"
ROOM"PROC_RSTS_PGOODS"
$SEC"1"
CDS_SEC"1"
CDS_LIB"mstr_discrete"
BOM_COST"PROC_SIDEBAND";
"A"
$PN"1"26;
"B"
$PN"2"3;
%"GND"
"1","(-8450,4775)","0","mstr_symbols","I15";
;
CDS_LIB"mstr_symbols"
SIZE"1B"
VOLTAGE"0.0V"
BODY_TYPE"PLUMBING"
HDL_POWER"GND";
"A\NAC"3;
%"GND"
"1","(-8150,4775)","0","mstr_symbols","I16";
;
CDS_LIB"mstr_symbols"
SIZE"1B"
VOLTAGE"0.0V"
BODY_TYPE"PLUMBING"
HDL_POWER"GND";
"A\NAC"4;
%"RES"
"2","(-8150,4950)","0","mstr_discrete","I17";
;
LOCATION"R25W175"
VALUE"1.00K"
TOLERANCE"1%"
PACK_TYPE"0402"
PART_NUMBER"G21796-026"
MATERIAL"CHIP"
WATTAGE"1/16W"
CDS_LOCATION"R25W175"
ROOM"PROC_RSTS_PGOODS"
$SEC"1"
CDS_SEC"1"
CDS_LIB"mstr_discrete"
BOM_COST"PROC_SIDEBAND";
"A"
$PN"1"42;
"B"
$PN"2"4;
%"RES"
"2","(-7100,3350)","0","mstr_discrete","I2";
;
MATERIAL"CHIP"
TOLERANCE"1%"
VALUE"1.00K"
LOCATION"R25W180"
PACK_TYPE"0402"
PART_NUMBER"G21796-026"
WATTAGE"1/16W"
CDS_LOCATION"R25W180"
BOM_COST"PROC_SIDEBAND"
CDS_LIB"mstr_discrete"
CDS_SEC"1"
$SEC"1"
ROOM"PROC_RSTS_PGOODS";
"A"
$PN"1"9;
"B"
$PN"2"39;
%"GND"
"1","(-7750,4825)","0","mstr_symbols","I20";
;
CDS_LIB"mstr_symbols"
SIZE"1B"
VOLTAGE"0.0V"
BODY_TYPE"PLUMBING"
HDL_POWER"GND";
"A\NAC"5;
%"GND"
"1","(-6550,5625)","0","mstr_symbols","I21";
;
VOLTAGE"0"
SIZE"1B"
CDS_LIB"mstr_symbols"
BODY_TYPE"PLUMBING"
HDL_POWER"GND";
"A\NAC"6;
%"P3V3_STBY"
"1","(-6550,6050)","0","mstr_symbols","I22";
;
CDS_LIB"mstr_symbols"
SIZE"1B"
VOLTAGE"3.3V"
BODY_TYPE"PLUMBING"
HDL_POWER"P3V3_STBY";
"G\NAC"7;
%"CAP"
"1","(-6550,5800)","0","mstr_discrete","I23";
;
PACK_TYPE"0402"
MATERIAL"X6S"
VOLTAGE"16V"
TOLERANCE"10%"
LOCATION"C25W92"
VALUE"1.0UF"
PART_NUMBER"D97712-011"
CDS_LOCATION"C25W92"
SEC_TYPE"0402"
CDS_LIB"mstr_discrete"
BOM_COST"PROC"
SEC"1"
ROOM"PROC_SIDEBAND"
CDS_SEC"1";
"A"
$PN"1"7;
"B"
$PN"2"6;
%"GND"
"1","(-5750,5575)","0","mstr_symbols","I25";
;
SIZE"1B"
CDS_LIB"mstr_symbols"
VOLTAGE"0"
BODY_TYPE"PLUMBING"
HDL_POWER"GND";
"A\NAC"8;
%"RES"
"1","(-6000,5450)","0","mstr_discrete","I26";
;
MATERIAL"CHIP"
WATTAGE"1/16W"
PACK_TYPE"0402"
TOLERANCE"1%"
VALUE"1.00K"
LOCATION"R25W166"
PART_NUMBER"G21796-026"
CDS_LOCATION"R25W166"
ROOM"PROC_SIDEBAND"
SEC"1"
BOM_COST"PROC_SIDEBAND"
CDS_LIB"mstr_discrete"
SEC_TYPE"0402"
CDS_SEC"1";
"B"
$PN"2"11;
"A"
$PN"1"30;
%"CAP_A"
"1","(-6050,5850)","0","dev_discrete","I27";
;
PACK_TYPE"0402V"
PART_NUMBER"A36096-030"
MATERIAL"X7R"
TOLERANCE"10%"
LOCATION"C25W93"
VALUE"0.1UF"
VOLTAGE"16V"
CDS_LOCATION"C25W93"
SEC"1"
SEC_TYPE"0402V"
CDS_SEC"1"
CDS_LIB"dev_discrete"
BOM_COST"PROC_SIDEBAND"
ROOM"PROC_SIDEBAND";
"B"
$PN"2"8;
"A"
$PN"1"25;
%"RES"
"2","(-5750,5850)","0","mstr_discrete","I28";
;
VALUE"100.0"
PART_NUMBER"G21796-017"
MATERIAL"CHIP"
PACK_TYPE"0402"
LOCATION"R25W165"
TOLERANCE"1%"
WATTAGE"1/16W"
CDS_LOCATION"R25W165"
ROOM"PROC_SIDEBAND"
SEC"1"
BOM_COST"PROC_SIDEBAND"
CDS_LIB"mstr_discrete"
SEC_TYPE"0402"
CDS_SEC"1";
"A"
$PN"1"25;
"B"
$PN"2"8;
%"RES"
"2","(-5750,6250)","0","mstr_discrete","I29";
;
LOCATION"R25W164"
PACK_TYPE"0402"
POP"NOPOP"
VALUE"49.9"
TOLERANCE"1%"
WATTAGE"1/16W"
MATERIAL"CHIP"
PART_NUMBER"G21796-047"
CDS_SEC"1"
ROOM"CPU0"
CDS_LIB"mstr_discrete"
BOM_COST"PROC_SIDEBAND"
SEC_TYPE"0402"
SEC"1"
CDS_LOCATION"R25W164";
"A"
$PN"1"10;
"B"
$PN"2"25;
%"P3V3_STBY"
"1","(-7100,3550)","0","mstr_symbols","I3";
;
VOLTAGE"3.3V"
SIZE"1B"
CDS_LIB"mstr_symbols"
BODY_TYPE"PLUMBING"
HDL_POWER"P3V3_STBY";
"G\NAC"9;
%"P1V05_PCH_STBY"
"1","(-5750,6450)","0","mstr_symbols","I30";
;
VOLTAGE"1.05V"
CDS_LIB"mstr_symbols"
BODY_TYPE"PLUMBING"
HDL_POWER"P1V05_PCH_STBY";
"G\NAC"10;
%"GND"
"1","(-5300,5375)","0","mstr_symbols","I32";
;
SIZE"1B"
CDS_LIB"mstr_symbols"
VOLTAGE"0"
BODY_TYPE"PLUMBING"
HDL_POWER"GND";
"A\NAC"11;
%"GTL2014"
"1","(-7200,5300)","2","mstr_digital","I33";
;
PART_NUMBER"D66151-001"
MATERIAL"IC"
LOCATION"U25W11"
CDS_LOCATION"U25W11"
ROOM"PROC_SIDEBAND"
SEC"1"
CDS_LIB"mstr_digital"
BOM_COST"PROC_SIDEBAND"
SEC_TYPE"SM"
PACK_TYPE"SM"
CDS_SEC"1";
"A0"
$PN"13"33;
"A1"
$PN"12"27;
"A3"
$PN"9"32;
"A2"
$PN"10"28;
"B2"
$PN"5"26;
"B3"
$PN"6"41;
"B0"
$PN"2"42;
"B1"
$PN"3"40;
"GND<1>"
$PN"8"5;
"GND<2>"
$PN"11"5;
"GND<0>"
$PN"7"5;
"VCC"
$PN"14"7;
"VREF"
$PN"4"25;
"DIR"
$PN"1"30;
%"374R2F-1-GP"
"1","(-5150,6225)","0","w_hdl","I36";
;
CDS_SEC"1"
$SEC"1"
CDS_LOCATION"R25W183"
VALUE"374R2F-1-GP"
LOCATION"R25W183"
ATTRIBUTE"374 OHM"
TOLERANCE"1%"
RATED"1/16W"
PACK_SIZE"0402"
PACK_TYPE"SMD-RG"
PART_NUMBER"64.37405.6DL"
CDS_LIB"w_hdl"
CDS_LMAN_SYM_OUTLINE"-50,75,50,-75";
"2"
$PN"2"25;
"1"
$PN"1"12;
%"P3V3_STBY"
"1","(-5150,6450)","0","mstr_symbols","I37";
;
CDS_LIB"mstr_symbols"
SIZE"1B"
VOLTAGE"3.3V"
BODY_TYPE"PLUMBING"
HDL_POWER"P3V3_STBY";
"G\NAC"12;
%"TTL3126"
"3","(-2900,5000)","0","mstr_ttl","I38";
;
MATERIAL"IC"
LOCATION"U25W16"
VALUE"74CBTLV3126"
PART_NUMBER"D18317-001"
POWER_GROUP"VCC=P3V3_STBY;GND=GND"
PACK_TYPE"QFNLF"
HAS_FIXED_SIZE"4B"
CDS_LIB"mstr_ttl"
ROOM"DEBUG"
CDS_LOCATION"U25W16";
"OE <3>"
$PN"1"
CDS_SEC"1"
$SEC"1"38;
"OE <2>"
$PN"4"
CDS_SEC"2"
$SEC"2"38;
"OE <1>"
$PN"10"
CDS_SEC"3"
$SEC"3"38;
"OE <0>"
$PN"13"
CDS_SEC"4"
$SEC"4"38;
"A <3>"
$PN"2"
CDS_SEC"1"
$SEC"1"37;
"A <2>"
$PN"5"
CDS_SEC"2"
$SEC"2"36;
"A <0>"
$PN"12"
CDS_SEC"4"
$SEC"4"47;
"A <1>"
$PN"9"
CDS_SEC"3"
$SEC"3"48;
"B <3>"
$PN"3"
CDS_SEC"1"
$SEC"1"49;
"B <2>"
$PN"6"
CDS_SEC"2"
$SEC"2"44;
"B <1>"
$PN"8"
CDS_SEC"3"
$SEC"3"45;
"B <0>"
$PN"11"
CDS_SEC"4"
$SEC"4"46;
%"P3V3_STBY"
"1","(-2250,4600)","0","mstr_symbols","I39";
;
VOLTAGE"3.3V"
CDS_LIB"mstr_symbols"
SIZE"1B"
BODY_TYPE"PLUMBING"
HDL_POWER"P3V3_STBY";
"G\NAC"13;
%"CAP_A"
"1","(-6700,3350)","0","dev_discrete","I4";
;
TOLERANCE"10%"
PACK_TYPE"0402V"
VOLTAGE"16V"
PART_NUMBER"A36096-030"
VALUE"0.1UF"
LOCATION"C25W97"
MATERIAL"X7R"
CDS_LOCATION"C25W97"
ROOM"CPU_FANS"
BOM_COST"SM_THERM"
SEC_TYPE"0402V"
SEC"1"
CDS_SEC"1"
CDS_LIB"dev_discrete";
"B"
$PN"2"15;
"A"
$PN"1"20;
%"CAP"
"1","(-2250,4400)","0","mstr_discrete","I40";
;
MATERIAL"X6S"
PART_NUMBER"D97712-011"
PACK_TYPE"0402"
VOLTAGE"16V"
VALUE"1.0UF"
LOCATION"C25W98"
TOLERANCE"10%"
CDS_SEC"1"
CDS_LIB"mstr_discrete"
SEC_TYPE"0402"
SEC"1"
ROOM"DEBUG"
CDS_LOCATION"C25W98";
"A"
$PN"1"13;
"B"
$PN"2"14;
%"GND"
"1","(-2250,4225)","0","mstr_symbols","I41";
;
SIZE"1B"
CDS_LIB"mstr_symbols"
VOLTAGE"0.0V"
BODY_TYPE"PLUMBING"
HDL_POWER"GND";
"A\NAC"14;
%"GND"
"1","(-6700,3175)","0","mstr_symbols","I5";
;
VOLTAGE"0.0V"
CDS_LIB"mstr_symbols"
SIZE"1B"
BODY_TYPE"PLUMBING"
HDL_POWER"GND";
"A\NAC"15;
%"FET_N"
"8","(-3250,3050)","0","mstr_discrete","I51";
;
CDS_SEC"1"
CDS_LOCATION"Q25W5"
LOCATION"Q25W5"
VALUE"2N7002"
MATERIAL"FET"
PART_NUMBER"C79254-001"
SEC_TYPE"SOT23LF"
SEC"1"
PACK_TYPE"SOT23LF"
CDS_LIB"mstr_discrete"
ROOM"HOT_SWAP";
"GATE"
$PN"1"29;
"DRN"
$PN"3"35;
"SRC"
$PN"2"16;
%"GND"
"1","(-3250,2775)","0","mstr_symbols","I52";
;
VOLTAGE"0.0V"
CDS_LIB"mstr_symbols"
SIZE"1B"
BODY_TYPE"PLUMBING"
HDL_POWER"GND";
"A\NAC"16;
%"RES"
"2","(-3550,3500)","0","mstr_discrete","I54";
;
CDS_SEC"1"
LOCATION"R25W185"
TOLERANCE"1%"
VALUE"4.75K"
WATTAGE"1/16W"
MATERIAL"CHIP"
PACK_TYPE"0402"
PART_NUMBER"G21796-072"
CDS_LOCATION"R25W185"
SEC"1"
SEC_TYPE"0402"
BOM_COST"SM_CONTROLLER"
CDS_LIB"mstr_discrete"
ROOM"BMC_MISC";
"A"
$PN"1"17;
"B"
$PN"2"35;
%"P3V3_STBY"
"1","(-3550,3700)","0","mstr_symbols","I55";
;
VOLTAGE"3.3V"
CDS_LIB"mstr_symbols"
SIZE"1B"
BODY_TYPE"PLUMBING"
HDL_POWER"P3V3_STBY";
"G\NAC"17;
%"TTL1G08"
"1","(-3400,4200)","0","mstr_ttl","I57";
;
CDS_SEC"1"
POWER_GROUP"VCC=P3V3_STBY;GND=GND;"
PART_NUMBER"D10321-001"
VALUE"NC7SZ08"
PACK_TYPE"SOTLF"
LOCATION"U25W18"
MATERIAL"IC"
CDS_LOCATION"U25W18"
ROOM"CAT_ERR"
SEC"1"
SEC_TYPE"SOTLF"
CDS_LIB"mstr_ttl"
BOM_COST"PROC_SIDEBAND";
"Y <SIZE-1..0>"
$PN"4"38;
"B <SIZE-1..0>"
$PN"2"35;
"A <SIZE-1..0>"
$PN"1"24;
%"P3V3_STBY"
"1","(-2700,4000)","0","mstr_symbols","I58";
;
CDS_LIB"mstr_symbols"
SIZE"1B"
VOLTAGE"3.3V"
BODY_TYPE"PLUMBING"
HDL_POWER"P3V3_STBY";
"G\NAC"18;
%"GND"
"1","(-2700,3625)","0","mstr_symbols","I59";
;
HDL_POWER"GND"
BODY_TYPE"PLUMBING"
CDS_LIB"mstr_symbols"
SIZE"1B"
VOLTAGE"0.0V";
"A\NAC"19;
%"P3V3_STBY"
"1","(-6700,3550)","0","mstr_symbols","I6";
;
CDS_LIB"mstr_symbols"
SIZE"1B"
VOLTAGE"3.3V"
BODY_TYPE"PLUMBING"
HDL_POWER"P3V3_STBY";
"G\NAC"20;
%"CAP_A"
"1","(-2700,3800)","0","dev_discrete","I60";
;
MATERIAL"X7R"
VALUE"0.1UF"
LOCATION"C25W100"
TOLERANCE"10%"
VOLTAGE"16V"
PACK_TYPE"0402V"
PART_NUMBER"A36096-030"
CDS_LOCATION"C25W100"
ROOM"PROC_SIDEBAND"
BOM_COST"PROC_SIDEBAND"
CDS_LIB"dev_discrete"
CDS_SEC"1"
SEC_TYPE"0402V"
SEC"1";
"B"
$PN"2"19;
"A"
$PN"1"18;
%"SW-SLIDE75-GP"
"1","(-2050,3325)","2","w_hdl","I63";
;
CDS_SEC"1"
CDS_LOCATION"S9W1"
LOCATION"S9W1"
VALUE"SW-SLIDE75-GP"
CDS_LIB"w_hdl"
CDS_LMAN_SYM_OUTLINE"-100,175,100,-175"
PART_NUMBER"62.40018.461"
SEC_TYPE"DISCRET-G6"
SEC"1"
PACK_TYPE"DISCRET-G6";
"7"
$PN"7"22;
"6"
$PN"6"22;
"NP2"
$PN"NP2"0;
"NP1"
$PN"NP1"0;
"5"
$PN"5"22;
"4"
$PN"4"22;
"3"
$PN"3"21;
"2"
$PN"2"35;
"1"
$PN"1"0;
%"GND"
"1","(-2300,3175)","0","mstr_symbols","I64";
;
HDL_POWER"GND"
BODY_TYPE"PLUMBING"
CDS_LIB"mstr_symbols"
SIZE"1B"
VOLTAGE"0.0V";
"A\NAC"21;
%"GND"
"1","(-2100,2875)","0","mstr_symbols","I65";
;
VOLTAGE"0.0V"
SIZE"1B"
CDS_LIB"mstr_symbols"
BODY_TYPE"PLUMBING"
HDL_POWER"GND";
"A\NAC"22;
%"RES"
"1","(-6000,5300)","0","mstr_discrete","I66";
;
CDS_SEC"1"
PART_NUMBER"G21497-005"
WATTAGE"1/16W"
PACK_TYPE"0402"
TOLERANCE"5%"
VALUE"0.0"
LOCATION"R25W187"
CDS_LIB"mstr_discrete"
BOM_COST"PROC_SIDEBAND"
MATERIAL"CHIP"
ROOM"CPU0"
SEC_TYPE"0402"
SEC"1"
CDS_LOCATION"R25W187";
"B"
$PN"2"31;
"A"
$PN"1"32;
%"RES"
"2","(-7100,4150)","0","mstr_discrete","I7";
;
WATTAGE"1/16W"
LOCATION"R25W179"
PACK_TYPE"0402"
PART_NUMBER"G21796-026"
MATERIAL"CHIP"
TOLERANCE"1%"
VALUE"1.00K"
CDS_LOCATION"R25W179"
ROOM"PROC_RSTS_PGOODS"
$SEC"1"
CDS_SEC"1"
CDS_LIB"mstr_discrete"
BOM_COST"PROC_SIDEBAND";
"A"
$PN"1"23;
"B"
$PN"2"43;
%"P3V3_STBY"
"1","(-7100,4350)","0","mstr_symbols","I8";
;
CDS_LIB"mstr_symbols"
SIZE"1B"
VOLTAGE"3.3V"
BODY_TYPE"PLUMBING"
HDL_POWER"P3V3_STBY";
"G\NAC"23;
%"CAP_A"
"1","(-6700,4150)","0","dev_discrete","I9";
;
LOCATION"C25W96"
VALUE"0.1UF"
VOLTAGE"16V"
TOLERANCE"10%"
PACK_TYPE"0402V"
PART_NUMBER"A36096-030"
MATERIAL"X7R"
CDS_LOCATION"C25W96"
CDS_LIB"dev_discrete"
CDS_SEC"1"
SEC"1"
SEC_TYPE"0402V"
BOM_COST"SM_THERM"
ROOM"CPU_FANS";
"B"
$PN"2"1;
"A"
$PN"1"2;
END.
